(kicad_pcb
	(version 20241229)
	(generator "pcbnew")
	(generator_version "9.0")
	(general
		(thickness 1.62)
		(legacy_teardrops no)
	)
	(paper "A3")
	(title_block
		(title "COM Express 7 Baseboard")
		(date "2025-02-04")
		(rev "1.1.2")
		(company "Antmicro Ltd")
		(comment 1 "www.antmicro.com")
		(comment 9 "footprints 437-442 of 802")
	)
	(layers
		(0 "F.Cu" signal)
		(4 "In1.Cu" signal)
		(6 "In2.Cu" signal)
		(8 "In3.Cu" signal)
		(10 "In4.Cu" signal)
		(12 "In5.Cu" signal)
		(14 "In6.Cu" signal)
		(2 "B.Cu" signal)
		(9 "F.Adhes" user "F.Adhesive")
		(11 "B.Adhes" user "B.Adhesive")
		(13 "F.Paste" user)
		(15 "B.Paste" user)
		(5 "F.SilkS" user "F.Silkscreen")
		(7 "B.SilkS" user "B.Silkscreen")
		(1 "F.Mask" user)
		(3 "B.Mask" user)
		(17 "Dwgs.User" user "User.Drawings")
		(19 "Cmts.User" user "User.Comments")
		(21 "Eco1.User" user "User.Eco1")
		(23 "Eco2.User" user "User.Eco2")
		(25 "Edge.Cuts" user)
		(27 "Margin" user)
		(31 "F.CrtYd" user "F.Courtyard")
		(29 "B.CrtYd" user "B.Courtyard")
		(35 "F.Fab" user)
		(33 "B.Fab" user)
	)
	(footprint "antmicro-footprints:R_0402_1005Metric"
		(layer "F.Cu")
		(at 215.98 133.12 -90)
		(descr "Resistor SMD 0402")
		(tags "resistor SMD 0402")
		(property "Reference" "R198"
			(at 2.44 -5.32 90)
			(layer "F.SilkS")
			(effects
				(font
					(size 0.7 0.7)
					(thickness 0.15)
				)
				(justify right bottom)
			)
		)
		(property "Value" "R_0R_0402"
			(at -1.011843 1.772047 90)
			(layer "F.Fab")
			(effects
				(font
					(size 0.7 0.7)
					(thickness 0.15)
				)
				(justify right bottom)
			)
		)
		(property "Datasheet" "https://industrial.panasonic.com/cdbs/www-data/pdf/RDA0000/AOA0000C301.pdf"
			(at 0 0 270)
			(layer "F.Fab")
			(hide yes)
			(effects
				(font
					(size 1.27 1.27)
					(thickness 0.15)
				)
			)
		)
		(property "Author" "Antmicro"
			(at 82.86 349.1 0)
			(layer "F.Fab")
			(hide yes)
			(effects
				(font
					(size 1 1)
					(thickness 0.15)
				)
			)
		)
		(property "Current" "1A"
			(at 82.86 349.1 0)
			(layer "F.Fab")
			(hide yes)
			(effects
				(font
					(size 1 1)
					(thickness 0.15)
				)
			)
		)
		(property "License" "Apache-2.0"
			(at 82.86 349.1 0)
			(layer "F.Fab")
			(hide yes)
			(effects
				(font
					(size 1 1)
					(thickness 0.15)
				)
			)
		)
		(property "MPN" "ERJ2GE0R00X"
			(at 82.86 349.1 0)
			(layer "F.Fab")
			(hide yes)
			(effects
				(font
					(size 1 1)
					(thickness 0.15)
				)
			)
		)
		(property "Manufacturer" "Panasonic"
			(at 82.86 349.1 0)
			(layer "F.Fab")
			(hide yes)
			(effects
				(font
					(size 1 1)
					(thickness 0.15)
				)
			)
		)
		(property "Public" "False"
			(at 82.86 349.1 0)
			(layer "F.Fab")
			(hide yes)
			(effects
				(font
					(size 1 1)
					(thickness 0.15)
				)
			)
		)
		(property "Tolerance" ""
			(at 82.86 349.1 0)
			(layer "F.Fab")
			(hide yes)
			(effects
				(font
					(size 1 1)
					(thickness 0.15)
				)
			)
		)
		(property "Val" "0R"
			(at 82.86 349.1 0)
			(layer "F.Fab")
			(hide yes)
			(effects
				(font
					(size 1 1)
					(thickness 0.15)
				)
			)
		)
		(sheetname "PCIe misc")
		(sheetfile "pcie_misc.kicad_sch")
		(attr smd)
		(fp_rect
			(start -0.925 -0.47)
			(end 0.925 0.47)
			(stroke
				(width 0.05)
				(type default)
			)
			(fill no)
			(layer "F.CrtYd")
		)
		(fp_rect
			(start -0.5 -0.25)
			(end 0.5 0.25)
			(stroke
				(width 0.15)
				(type solid)
			)
			(fill no)
			(layer "F.Fab")
		)
		(pad "1" smd roundrect
			(at -0.48 0 270)
			(size 0.59 0.64)
			(layers "F.Cu" "F.Mask" "F.Paste")
			(roundrect_rratio 0.25)
			(net 617 "/PCIe misc/DIF3+")
			(pintype "passive")
			(teardrops
				(best_length_ratio 0.2)
				(max_length 1)
				(best_width_ratio 0.9)
				(max_width 2)
				(curved_edges yes)
				(filter_ratio 0.9)
				(enabled yes)
				(allow_two_segments yes)
				(prefer_zone_connections yes)
			)
		)
		(pad "2" smd roundrect
			(at 0.48 0 270)
			(size 0.59 0.64)
			(layers "F.Cu" "F.Mask" "F.Paste")
			(roundrect_rratio 0.25)
			(net 203 "/Backplane/PCIe_{REF}.CK+")
			(pintype "passive")
			(teardrops
				(best_length_ratio 0.2)
				(max_length 1)
				(best_width_ratio 0.9)
				(max_width 2)
				(curved_edges yes)
				(filter_ratio 0.9)
				(enabled yes)
				(allow_two_segments yes)
				(prefer_zone_connections yes)
			)
		)
	)
	(footprint "antmicro-footprints:R_0402_1005Metric"
		(layer "F.Cu")
		(at 120.2 91.26 -90)
		(descr "Resistor SMD 0402")
		(tags "resistor SMD 0402")
		(property "Reference" "R13"
			(at 0.8 -0.4 90)
			(layer "F.SilkS")
			(effects
				(font
					(size 0.7 0.7)
					(thickness 0.15)
				)
				(justify right bottom)
			)
		)
		(property "Value" "R_2k2_0402"
			(at -1.011843 1.772047 90)
			(layer "F.Fab")
			(effects
				(font
					(size 0.7 0.7)
					(thickness 0.15)
				)
				(justify right bottom)
			)
		)
		(property "Datasheet" "https://www.bourns.com/docs/product-datasheets/cr.pdf"
			(at 0 0 270)
			(layer "F.Fab")
			(hide yes)
			(effects
				(font
					(size 1.27 1.27)
					(thickness 0.15)
				)
			)
		)
		(property "Author" "Antmicro"
			(at 28.94 211.46 0)
			(layer "F.Fab")
			(hide yes)
			(effects
				(font
					(size 1 1)
					(thickness 0.15)
				)
			)
		)
		(property "License" "Apache-2.0"
			(at 28.94 211.46 0)
			(layer "F.Fab")
			(hide yes)
			(effects
				(font
					(size 1 1)
					(thickness 0.15)
				)
			)
		)
		(property "MPN" "CR0402-FX-2201GLF"
			(at 28.94 211.46 0)
			(layer "F.Fab")
			(hide yes)
			(effects
				(font
					(size 1 1)
					(thickness 0.15)
				)
			)
		)
		(property "Manufacturer" "Bourns"
			(at 28.94 211.46 0)
			(layer "F.Fab")
			(hide yes)
			(effects
				(font
					(size 1 1)
					(thickness 0.15)
				)
			)
		)
		(property "Public" "False"
			(at 28.94 211.46 0)
			(layer "F.Fab")
			(hide yes)
			(effects
				(font
					(size 1 1)
					(thickness 0.15)
				)
			)
		)
		(property "Tolerance" "1%"
			(at 28.94 211.46 0)
			(layer "F.Fab")
			(hide yes)
			(effects
				(font
					(size 1 1)
					(thickness 0.15)
				)
			)
		)
		(property "Val" "2k2"
			(at 28.94 211.46 0)
			(layer "F.Fab")
			(hide yes)
			(effects
				(font
					(size 1 1)
					(thickness 0.15)
				)
			)
		)
		(sheetname "2xUSB3.0+RJ45")
		(sheetfile "usb3+rj45.kicad_sch")
		(attr smd)
		(fp_rect
			(start -0.925 -0.47)
			(end 0.925 0.47)
			(stroke
				(width 0.05)
				(type default)
			)
			(fill no)
			(layer "F.CrtYd")
		)
		(fp_rect
			(start -0.5 -0.25)
			(end 0.5 0.25)
			(stroke
				(width 0.15)
				(type solid)
			)
			(fill no)
			(layer "F.Fab")
		)
		(pad "1" smd roundrect
			(at -0.48 0 270)
			(size 0.59 0.64)
			(layers "F.Cu" "F.Mask" "F.Paste")
			(roundrect_rratio 0.25)
			(net 1 "GND")
			(pintype "passive")
			(teardrops
				(best_length_ratio 0.2)
				(max_length 1)
				(best_width_ratio 0.9)
				(max_width 2)
				(curved_edges yes)
				(filter_ratio 0.9)
				(enabled yes)
				(allow_two_segments yes)
				(prefer_zone_connections yes)
			)
		)
		(pad "2" smd roundrect
			(at 0.48 0 270)
			(size 0.59 0.64)
			(layers "F.Cu" "F.Mask" "F.Paste")
			(roundrect_rratio 0.25)
			(net 548 "/2xUSB3.0+RJ45/P2_ISET")
			(pintype "passive")
			(teardrops
				(best_length_ratio 0.2)
				(max_length 1)
				(best_width_ratio 0.9)
				(max_width 2)
				(curved_edges yes)
				(filter_ratio 0.9)
				(enabled yes)
				(allow_two_segments yes)
				(prefer_zone_connections yes)
			)
		)
	)
	(footprint "antmicro-footprints:R_0402_1005Metric"
		(layer "F.Cu")
		(at 155.299 168.36 180)
		(descr "Resistor SMD 0402")
		(tags "resistor SMD 0402")
		(property "Reference" "R64"
			(at -4.551 18.1 0)
			(layer "F.SilkS")
			(effects
				(font
					(size 0.7 0.7)
					(thickness 0.15)
				)
				(justify left bottom)
			)
		)
		(property "Value" "R_220R_0402"
			(at -1.011843 1.772047 0)
			(layer "F.Fab")
			(effects
				(font
					(size 0.7 0.7)
					(thickness 0.15)
				)
				(justify right bottom)
			)
		)
		(property "Datasheet" "https://www.bourns.com/docs/product-datasheets/cr.pdf"
			(at 0 0 180)
			(layer "F.Fab")
			(hide yes)
			(effects
				(font
					(size 1.27 1.27)
					(thickness 0.15)
				)
			)
		)
		(property "Author" "Antmicro"
			(at 310.598 336.72 0)
			(layer "F.Fab")
			(hide yes)
			(effects
				(font
					(size 1 1)
					(thickness 0.15)
				)
			)
		)
		(property "License" "Apache-2.0"
			(at 310.598 336.72 0)
			(layer "F.Fab")
			(hide yes)
			(effects
				(font
					(size 1 1)
					(thickness 0.15)
				)
			)
		)
		(property "MPN" "CR0402-FX-2200GLF"
			(at 310.598 336.72 0)
			(layer "F.Fab")
			(hide yes)
			(effects
				(font
					(size 1 1)
					(thickness 0.15)
				)
			)
		)
		(property "Manufacturer" "Bourns"
			(at 310.598 336.72 0)
			(layer "F.Fab")
			(hide yes)
			(effects
				(font
					(size 1 1)
					(thickness 0.15)
				)
			)
		)
		(property "Public" "False"
			(at 310.598 336.72 0)
			(layer "F.Fab")
			(hide yes)
			(effects
				(font
					(size 1 1)
					(thickness 0.15)
				)
			)
		)
		(property "Tolerance" "1%"
			(at 310.598 336.72 0)
			(layer "F.Fab")
			(hide yes)
			(effects
				(font
					(size 1 1)
					(thickness 0.15)
				)
			)
		)
		(property "Val" "220R"
			(at 310.598 336.72 0)
			(layer "F.Fab")
			(hide yes)
			(effects
				(font
					(size 1 1)
					(thickness 0.15)
				)
			)
		)
		(sheetname "2xSFP+")
		(sheetfile "2xSFP+.kicad_sch")
		(attr smd)
		(fp_rect
			(start -0.925 -0.47)
			(end 0.925 0.47)
			(stroke
				(width 0.05)
				(type default)
			)
			(fill no)
			(layer "F.CrtYd")
		)
		(fp_rect
			(start -0.5 -0.25)
			(end 0.5 0.25)
			(stroke
				(width 0.15)
				(type solid)
			)
			(fill no)
			(layer "F.Fab")
		)
		(pad "1" smd roundrect
			(at -0.48 0 180)
			(size 0.59 0.64)
			(layers "F.Cu" "F.Mask" "F.Paste")
			(roundrect_rratio 0.25)
			(net 929 "/2xSFP+/SFP1_LEDG")
			(pintype "passive")
			(teardrops
				(best_length_ratio 0.2)
				(max_length 1)
				(best_width_ratio 0.9)
				(max_width 2)
				(curved_edges yes)
				(filter_ratio 0.9)
				(enabled yes)
				(allow_two_segments yes)
				(prefer_zone_connections yes)
			)
		)
		(pad "2" smd roundrect
			(at 0.48 0 180)
			(size 0.59 0.64)
			(layers "F.Cu" "F.Mask" "F.Paste")
			(roundrect_rratio 0.25)
			(net 932 "Net-(D7-C)")
			(pintype "passive")
			(teardrops
				(best_length_ratio 0.2)
				(max_length 1)
				(best_width_ratio 0.9)
				(max_width 2)
				(curved_edges yes)
				(filter_ratio 0.9)
				(enabled yes)
				(allow_two_segments yes)
				(prefer_zone_connections yes)
			)
		)
	)
	(footprint "antmicro-footprints:R_0402_1005Metric"
		(layer "F.Cu")
		(at 178.4 145.999999 180)
		(descr "Resistor SMD 0402")
		(tags "resistor SMD 0402")
		(property "Reference" "R42"
			(at -2.95 -0.45 0)
			(layer "F.SilkS")
			(effects
				(font
					(size 0.7 0.7)
					(thickness 0.15)
				)
				(justify right bottom)
			)
		)
		(property "Value" "R_0R_0402"
			(at -1.011843 1.772046 0)
			(layer "F.Fab")
			(effects
				(font
					(size 0.7 0.7)
					(thickness 0.15)
				)
				(justify right bottom)
			)
		)
		(property "Datasheet" "https://industrial.panasonic.com/cdbs/www-data/pdf/RDA0000/AOA0000C301.pdf"
			(at 0 0 0)
			(layer "F.Fab")
			(hide yes)
			(effects
				(font
					(size 1.27 1.27)
					(thickness 0.15)
				)
			)
		)
		(property "Author" "Antmicro"
			(at 337.9 334.52 0)
			(layer "F.Fab")
			(hide yes)
			(effects
				(font
					(size 1 1)
					(thickness 0.15)
				)
			)
		)
		(property "Current" "1A"
			(at 337.9 334.52 0)
			(layer "F.Fab")
			(hide yes)
			(effects
				(font
					(size 1 1)
					(thickness 0.15)
				)
			)
		)
		(property "License" "Apache-2.0"
			(at 337.9 334.52 0)
			(layer "F.Fab")
			(hide yes)
			(effects
				(font
					(size 1 1)
					(thickness 0.15)
				)
			)
		)
		(property "MPN" "ERJ2GE0R00X"
			(at 337.9 334.52 0)
			(layer "F.Fab")
			(hide yes)
			(effects
				(font
					(size 1 1)
					(thickness 0.15)
				)
			)
		)
		(property "Manufacturer" "Panasonic"
			(at 337.9 334.52 0)
			(layer "F.Fab")
			(hide yes)
			(effects
				(font
					(size 1 1)
					(thickness 0.15)
				)
			)
		)
		(property "Public" "False"
			(at 337.9 334.52 0)
			(layer "F.Fab")
			(hide yes)
			(effects
				(font
					(size 1 1)
					(thickness 0.15)
				)
			)
		)
		(property "Tolerance" ""
			(at 337.9 334.52 0)
			(layer "F.Fab")
			(hide yes)
			(effects
				(font
					(size 1 1)
					(thickness 0.15)
				)
			)
		)
		(property "Val" "0R"
			(at 337.9 334.52 0)
			(layer "F.Fab")
			(hide yes)
			(effects
				(font
					(size 1 1)
					(thickness 0.15)
				)
			)
		)
		(sheetname "2xSFP+")
		(sheetfile "2xSFP+.kicad_sch")
		(attr smd)
		(fp_rect
			(start -0.925 -0.47)
			(end 0.925 0.47)
			(stroke
				(width 0.05)
				(type default)
			)
			(fill no)
			(layer "F.CrtYd")
		)
		(fp_rect
			(start -0.5 -0.25)
			(end 0.5 0.25)
			(stroke
				(width 0.15)
				(type solid)
			)
			(fill no)
			(layer "F.Fab")
		)
		(pad "1" smd roundrect
			(at -0.48 0 180)
			(size 0.59 0.64)
			(layers "F.Cu" "F.Mask" "F.Paste")
			(roundrect_rratio 0.25)
			(net 492 "/2xSFP+/MOD1_ABS")
			(pintype "passive")
			(teardrops
				(best_length_ratio 0.2)
				(max_length 1)
				(best_width_ratio 0.9)
				(max_width 2)
				(curved_edges yes)
				(filter_ratio 0.9)
				(enabled yes)
				(allow_two_segments yes)
				(prefer_zone_connections yes)
			)
		)
		(pad "2" smd roundrect
			(at 0.48 0 180)
			(size 0.59 0.64)
			(layers "F.Cu" "F.Mask" "F.Paste")
			(roundrect_rratio 0.25)
			(net 894 "Net-(J2B-MOD_{ABS})")
			(pintype "passive")
			(teardrops
				(best_length_ratio 0.2)
				(max_length 1)
				(best_width_ratio 0.9)
				(max_width 2)
				(curved_edges yes)
				(filter_ratio 0.9)
				(enabled yes)
				(allow_two_segments yes)
				(prefer_zone_connections yes)
			)
		)
	)
	(footprint "antmicro-footprints:R_0402_1005Metric"
		(layer "F.Cu")
		(at 311.765499 97.4365 -90)
		(descr "Resistor SMD 0402")
		(tags "resistor SMD 0402")
		(property "Reference" "R108"
			(at -10.1265 -4.734501 90)
			(layer "F.SilkS")
			(effects
				(font
					(size 0.7 0.7)
					(thickness 0.15)
				)
				(justify right bottom)
			)
		)
		(property "Value" "R_10k_0402"
			(at -1.011843 1.772047 90)
			(layer "F.Fab")
			(effects
				(font
					(size 0.7 0.7)
					(thickness 0.15)
				)
				(justify right bottom)
			)
		)
		(property "Datasheet" "https://www.bourns.com/docs/product-datasheets/cr.pdf"
			(at 0 0 270)
			(layer "F.Fab")
			(hide yes)
			(effects
				(font
					(size 1.27 1.27)
					(thickness 0.15)
				)
			)
		)
		(property "Author" "Antmicro"
			(at 214.328999 409.201999 0)
			(layer "F.Fab")
			(hide yes)
			(effects
				(font
					(size 1 1)
					(thickness 0.15)
				)
			)
		)
		(property "License" "Apache-2.0"
			(at 214.328999 409.201999 0)
			(layer "F.Fab")
			(hide yes)
			(effects
				(font
					(size 1 1)
					(thickness 0.15)
				)
			)
		)
		(property "MPN" "CR0402-FX-1002GLF"
			(at 214.328999 409.201999 0)
			(layer "F.Fab")
			(hide yes)
			(effects
				(font
					(size 1 1)
					(thickness 0.15)
				)
			)
		)
		(property "Manufacturer" "Bourns"
			(at 214.328999 409.201999 0)
			(layer "F.Fab")
			(hide yes)
			(effects
				(font
					(size 1 1)
					(thickness 0.15)
				)
			)
		)
		(property "Public" "False"
			(at 214.328999 409.201999 0)
			(layer "F.Fab")
			(hide yes)
			(effects
				(font
					(size 1 1)
					(thickness 0.15)
				)
			)
		)
		(property "Tolerance" "1%"
			(at 214.328999 409.201999 0)
			(layer "F.Fab")
			(hide yes)
			(effects
				(font
					(size 1 1)
					(thickness 0.15)
				)
			)
		)
		(property "Val" "10k"
			(at 214.328999 409.201999 0)
			(layer "F.Fab")
			(hide yes)
			(effects
				(font
					(size 1 1)
					(thickness 0.15)
				)
			)
		)
		(sheetname "Power")
		(sheetfile "power.kicad_sch")
		(attr smd)
		(fp_rect
			(start -0.925 -0.47)
			(end 0.925 0.47)
			(stroke
				(width 0.05)
				(type default)
			)
			(fill no)
			(layer "F.CrtYd")
		)
		(fp_rect
			(start -0.5 -0.25)
			(end 0.5 0.25)
			(stroke
				(width 0.15)
				(type solid)
			)
			(fill no)
			(layer "F.Fab")
		)
		(pad "1" smd roundrect
			(at -0.48 0 270)
			(size 0.59 0.64)
			(layers "F.Cu" "F.Mask" "F.Paste")
			(roundrect_rratio 0.25)
			(net 1 "GND")
			(pintype "passive")
			(teardrops
				(best_length_ratio 0.2)
				(max_length 1)
				(best_width_ratio 0.9)
				(max_width 2)
				(curved_edges yes)
				(filter_ratio 0.9)
				(enabled yes)
				(allow_two_segments yes)
				(prefer_zone_connections yes)
			)
		)
		(pad "2" smd roundrect
			(at 0.48 0 270)
			(size 0.59 0.64)
			(layers "F.Cu" "F.Mask" "F.Paste")
			(roundrect_rratio 0.25)
			(net 584 "Net-(U21-EN)")
			(pintype "passive")
			(teardrops
				(best_length_ratio 0.2)
				(max_length 1)
				(best_width_ratio 0.9)
				(max_width 2)
				(curved_edges yes)
				(filter_ratio 0.9)
				(enabled yes)
				(allow_two_segments yes)
				(prefer_zone_connections yes)
			)
		)
	)
	(footprint "antmicro-footprints:R_0402_1005Metric"
		(layer "F.Cu")
		(at 129.9 81.760001 -90)
		(descr "Resistor SMD 0402")
		(tags "resistor SMD 0402")
		(property "Reference" "R235"
			(at -3.650001 -0.45 90)
			(layer "F.SilkS")
			(effects
				(font
					(size 0.7 0.7)
					(thickness 0.15)
				)
				(justify right bottom)
			)
		)
		(property "Value" "R_0R_0402"
			(at -1.011843 1.772047 90)
			(layer "F.Fab")
			(effects
				(font
					(size 0.7 0.7)
					(thickness 0.15)
				)
				(justify right bottom)
			)
		)
		(property "Datasheet" "https://industrial.panasonic.com/cdbs/www-data/pdf/RDA0000/AOA0000C301.pdf"
			(at 0 0 270)
			(layer "F.Fab")
			(hide yes)
			(effects
				(font
					(size 1.27 1.27)
					(thickness 0.15)
				)
			)
		)
		(property "Author" "Antmicro"
			(at 48.139999 211.660001 0)
			(layer "F.Fab")
			(hide yes)
			(effects
				(font
					(size 1 1)
					(thickness 0.15)
				)
			)
		)
		(property "Current" "1A"
			(at 48.139999 211.660001 0)
			(layer "F.Fab")
			(hide yes)
			(effects
				(font
					(size 1 1)
					(thickness 0.15)
				)
			)
		)
		(property "License" "Apache-2.0"
			(at 48.139999 211.660001 0)
			(layer "F.Fab")
			(hide yes)
			(effects
				(font
					(size 1 1)
					(thickness 0.15)
				)
			)
		)
		(property "MPN" "ERJ2GE0R00X"
			(at 48.139999 211.660001 0)
			(layer "F.Fab")
			(hide yes)
			(effects
				(font
					(size 1 1)
					(thickness 0.15)
				)
			)
		)
		(property "Manufacturer" "Panasonic"
			(at 48.139999 211.660001 0)
			(layer "F.Fab")
			(hide yes)
			(effects
				(font
					(size 1 1)
					(thickness 0.15)
				)
			)
		)
		(property "Public" "False"
			(at 48.139999 211.660001 0)
			(layer "F.Fab")
			(hide yes)
			(effects
				(font
					(size 1 1)
					(thickness 0.15)
				)
			)
		)
		(property "Tolerance" ""
			(at 48.139999 211.660001 0)
			(layer "F.Fab")
			(hide yes)
			(effects
				(font
					(size 1 1)
					(thickness 0.15)
				)
			)
		)
		(property "Val" "0R"
			(at 48.139999 211.660001 0)
			(layer "F.Fab")
			(hide yes)
			(effects
				(font
					(size 1 1)
					(thickness 0.15)
				)
			)
		)
		(sheetname "GPIO expander")
		(sheetfile "gpio_exp.kicad_sch")
		(attr smd)
		(fp_rect
			(start -0.925 -0.47)
			(end 0.925 0.47)
			(stroke
				(width 0.05)
				(type default)
			)
			(fill no)
			(layer "F.CrtYd")
		)
		(fp_rect
			(start -0.5 -0.25)
			(end 0.5 0.25)
			(stroke
				(width 0.15)
				(type solid)
			)
			(fill no)
			(layer "F.Fab")
		)
		(pad "1" smd roundrect
			(at -0.48 0 270)
			(size 0.59 0.64)
			(layers "F.Cu" "F.Mask" "F.Paste")
			(roundrect_rratio 0.25)
			(net 359 "/Com Express 7 MGMT/SMBus.~{INT}")
			(pintype "passive")
			(teardrops
				(best_length_ratio 0.2)
				(max_length 1)
				(best_width_ratio 0.9)
				(max_width 2)
				(curved_edges yes)
				(filter_ratio 0.9)
				(enabled yes)
				(allow_two_segments yes)
				(prefer_zone_connections yes)
			)
		)
		(pad "2" smd roundrect
			(at 0.48 0 270)
			(size 0.59 0.64)
			(layers "F.Cu" "F.Mask" "F.Paste")
			(roundrect_rratio 0.25)
			(net 636 "Net-(U41-~{INT})")
			(pintype "passive")
			(teardrops
				(best_length_ratio 0.2)
				(max_length 1)
				(best_width_ratio 0.9)
				(max_width 2)
				(curved_edges yes)
				(filter_ratio 0.9)
				(enabled yes)
				(allow_two_segments yes)
				(prefer_zone_connections yes)
			)
		)
	)
)
